# T6G (Grand Teton) — schematic netlist excerpt (pin names and nets, part order shuffled) for the footprints in the layout excerpt that follows; sources: Cadence DE-HDL packaged netlist, KiCad conversion of 04192023_DAF0TMB3IC0_F0TG_MB_C_brd_V02_OCP.brd

PC407_4  Q_CAP  1UF 25V 10% X6S  pkg C0402  page 219 : A = SW_P12V_AUX_PVDDCR_CPU1_P1_FLT ; B = GND

(kicad_pcb
	(version 20260206)
	(generator "pcbnew")
	(generator_version "10.0")
	(general
		(thickness 1.6)
		(legacy_teardrops no)
	)
	(paper "A4")
	(title_block
		(title "04192023_DAF0TMB3IC0_F0TG_MB_C_brd_V02_OCP.brd")
		(comment 1 "Grand Teton / footprints 28-29 of 8354")
	)
	(layers
		(0 "F.Cu" signal "TOP")
		(4 "In1.Cu" signal "GND")
		(6 "In2.Cu" signal "IN1")
		(8 "In3.Cu" signal "GND1")
		(10 "In4.Cu" signal "IN2")
		(12 "In5.Cu" signal "GND2")
		(14 "In6.Cu" signal "IN3")
		(16 "In7.Cu" signal "GND3")
		(18 "In8.Cu" signal "VCC")
		(20 "In9.Cu" signal "VCC1")
		(22 "In10.Cu" signal "GND4")
		(24 "In11.Cu" signal "IN4")
		(26 "In12.Cu" signal "GND5")
		(28 "In13.Cu" signal "IN5")
		(30 "In14.Cu" signal "GND6")
		(32 "In15.Cu" signal "IN6")
		(34 "In16.Cu" signal "GND7")
		(2 "B.Cu" signal "BOTTOM")
		(9 "F.Adhes" user "F.Adhesive")
		(11 "B.Adhes" user "B.Adhesive")
		(13 "F.Paste" user "Package Geometry/Pastemask Top")
		(15 "B.Paste" user "Package Geometry/Pastemask Bottom")
		(5 "F.SilkS" user "Ref Des/Silkscreen Top")
		(7 "B.SilkS" user "Ref Des/Silkscreen Bottom")
		(1 "F.Mask" user "Board Geometry/Soldermask Top")
		(3 "B.Mask" user "Board Geometry/Soldermask Bottom")
		(17 "Dwgs.User" user "User.Drawings")
		(19 "Cmts.User" user "User.Comments")
		(21 "Eco1.User" user "User.Eco1")
		(23 "Eco2.User" user "User.Eco2")
		(25 "Edge.Cuts" user "Board Geometry/Outline")
		(27 "Margin" user)
		(31 "F.CrtYd" user "Package Geometry/Place Bound Top")
		(29 "B.CrtYd" user "Package Geometry/Place Bound Bottom")
		(35 "F.Fab" user "Ref Des/Assembly Top")
		(33 "B.Fab" user "Ref Des/Assembly Bottom")
	)
	(footprint ""
		(layer "F.Cu")
		(at 65.50914 -346.87129 -90)
		(property "Reference" "PC407_4"
			(at 0 0 270)
			(layer "F.SilkS")
			(hide yes)
			(effects
				(font
					(size 1.27 1.27)
				)
			)
		)
		(property "Value" ""
			(at 0 0 270)
			(layer "F.Fab")
			(effects
				(font
					(size 1.27 1.27)
				)
			)
		)
		(duplicate_pad_numbers_are_jumpers no)
		(fp_line
			(start -0.7874 0.4064)
			(end -0.7874 -0.4064)
			(stroke
				(width 0.1524)
				(type default)
			)
			(layer "F.SilkS")
		)
		(fp_line
			(start 0.7874 0.4064)
			(end -0.7874 0.4064)
			(stroke
				(width 0.1524)
				(type default)
			)
			(layer "F.SilkS")
		)
		(fp_line
			(start -0.7874 -0.4064)
			(end 0.7874 -0.4064)
			(stroke
				(width 0.1524)
				(type default)
			)
			(layer "F.SilkS")
		)
		(fp_line
			(start 0.7874 -0.4064)
			(end 0.7874 0.4064)
			(stroke
				(width 0.1524)
				(type default)
			)
			(layer "F.SilkS")
		)
		(fp_line
			(start -0.67945 0.3048)
			(end -0.67945 -0.305054)
			(stroke
				(width 0.1)
				(type default)
			)
			(layer "F.Fab")
		)
		(fp_line
			(start -0.12065 0.3048)
			(end -0.67945 0.3048)
			(stroke
				(width 0.1)
				(type default)
			)
			(layer "F.Fab")
		)
		(fp_line
			(start 0.120396 0.3048)
			(end 0.120396 0.2794)
			(stroke
				(width 0.1)
				(type default)
			)
			(layer "F.Fab")
		)
		(fp_line
			(start 0.67945 0.3048)
			(end 0.120396 0.3048)
			(stroke
				(width 0.1)
				(type default)
			)
			(layer "F.Fab")
		)
		(fp_line
			(start -0.12065 0.2794)
			(end -0.12065 0.3048)
			(stroke
				(width 0.1)
				(type default)
			)
			(layer "F.Fab")
		)
		(fp_line
			(start 0.120396 0.2794)
			(end -0.12065 0.2794)
			(stroke
				(width 0.1)
				(type default)
			)
			(layer "F.Fab")
		)
		(fp_line
			(start -0.12065 -0.2794)
			(end 0.12065 -0.2794)
			(stroke
				(width 0.1)
				(type default)
			)
			(layer "F.Fab")
		)
		(fp_line
			(start 0.12065 -0.2794)
			(end 0.12065 -0.3048)
			(stroke
				(width 0.1)
				(type default)
			)
			(layer "F.Fab")
		)
		(fp_line
			(start 0.12065 -0.3048)
			(end 0.67945 -0.3048)
			(stroke
				(width 0.1)
				(type default)
			)
			(layer "F.Fab")
		)
		(fp_line
			(start 0.67945 -0.3048)
			(end 0.67945 0.3048)
			(stroke
				(width 0.1)
				(type default)
			)
			(layer "F.Fab")
		)
		(fp_line
			(start -0.67945 -0.305054)
			(end -0.12065 -0.305054)
			(stroke
				(width 0.1)
				(type default)
			)
			(layer "F.Fab")
		)
		(fp_line
			(start -0.12065 -0.305054)
			(end -0.12065 -0.2794)
			(stroke
				(width 0.1)
				(type default)
			)
			(layer "F.Fab")
		)
		(pad "1" smd circle
			(at -0.40005 0 270)
			(size 0 0)
			(layers "F.Cu" "F.Mask" "F.Paste")
			(net "SW_P12V_AUX_PVDDCR_CPU1_P1_FLT")
		)
		(pad "2" smd circle
			(at 0.40005 0 270)
			(size 0 0)
			(layers "F.Cu" "F.Mask" "F.Paste")
			(net "GND")
		)
	)
	(footprint ""
		(layer "F.Cu")
		(at 433.05222 -418.942266 180)
		(property "Reference" ""
			(at 0 0 180)
			(layer "F.SilkS")
			(hide yes)
			(effects
				(font
					(size 1.27 1.27)
				)
			)
		)
		(property "Value" ""
			(at 0 0 180)
			(layer "F.Fab")
			(effects
				(font
					(size 1.27 1.27)
				)
			)
		)
		(duplicate_pad_numbers_are_jumpers no)
		(pad "1" smd circle
			(at 0 0 180)
			(size 0.9906 0.9906)
			(layers "F.Cu" "F.Mask" "F.Paste")
			(net "Net_2241")
		)
		(zone
			(layer "F.Cu")
			(hatch none 0.5)
			(connect_pads
				(clearance 0)
			)
			(min_thickness 0.25)
			(keepout
				(tracks not_allowed)
				(vias allowed)
				(pads allowed)
				(copperpour not_allowed)
				(footprints allowed)
			)
			(placement
				(enabled no)
				(sheetname "")
			)
			(fill
				(thermal_gap 0.5)
				(thermal_bridge_width 0.5)
				(island_removal_mode 0)
			)
			(polygon
				(pts
					(arc
						(start 434.67782 -418.942266)
						(mid 431.42662 -418.942266)
						(end 434.67782 -418.942266)
					)
				)
			)
		)
	)
)
